# T6G (Grand Teton) — schematic netlist excerpt (pin names and nets, part order shuffled) for the footprints in the layout excerpt that follows; sources: Cadence DE-HDL packaged netlist, KiCad conversion of 04192023_DAF0TMB3IC0_F0TG_MB_C_brd_V02_OCP.brd

J81  PICOPROBE_BXA  DELTA-L 4.0 EMPTY  pkg TRIANG_LAUNCH_3PXB  page 229
  \1_p\  = DELTA_L_85_10INCH_TOP_DN
  \2_n\  = DELTA_L_85_10INCH_TOP_DP
  \3_g\  = DELTA_L_GND_1

(kicad_pcb
	(version 20260206)
	(generator "pcbnew")
	(generator_version "10.0")
	(general
		(thickness 1.6)
		(legacy_teardrops no)
	)
	(paper "A4")
	(title_block
		(title "04192023_DAF0TMB3IC0_F0TG_MB_C_brd_V02_OCP.brd")
		(comment 1 "Grand Teton / footprints 3790-3790 of 8354")
	)
	(layers
		(0 "F.Cu" signal "TOP")
		(4 "In1.Cu" signal "GND")
		(6 "In2.Cu" signal "IN1")
		(8 "In3.Cu" signal "GND1")
		(10 "In4.Cu" signal "IN2")
		(12 "In5.Cu" signal "GND2")
		(14 "In6.Cu" signal "IN3")
		(16 "In7.Cu" signal "GND3")
		(18 "In8.Cu" signal "VCC")
		(20 "In9.Cu" signal "VCC1")
		(22 "In10.Cu" signal "GND4")
		(24 "In11.Cu" signal "IN4")
		(26 "In12.Cu" signal "GND5")
		(28 "In13.Cu" signal "IN5")
		(30 "In14.Cu" signal "GND6")
		(32 "In15.Cu" signal "IN6")
		(34 "In16.Cu" signal "GND7")
		(2 "B.Cu" signal "BOTTOM")
		(9 "F.Adhes" user "F.Adhesive")
		(11 "B.Adhes" user "B.Adhesive")
		(13 "F.Paste" user "Package Geometry/Pastemask Top")
		(15 "B.Paste" user "Package Geometry/Pastemask Bottom")
		(5 "F.SilkS" user "Ref Des/Silkscreen Top")
		(7 "B.SilkS" user "Ref Des/Silkscreen Bottom")
		(1 "F.Mask" user "Board Geometry/Soldermask Top")
		(3 "B.Mask" user "Board Geometry/Soldermask Bottom")
		(17 "Dwgs.User" user "User.Drawings")
		(19 "Cmts.User" user "User.Comments")
		(21 "Eco1.User" user "User.Eco1")
		(23 "Eco2.User" user "User.Eco2")
		(25 "Edge.Cuts" user "Board Geometry/Outline")
		(27 "Margin" user)
		(31 "F.CrtYd" user "Package Geometry/Place Bound Top")
		(29 "B.CrtYd" user "Package Geometry/Place Bound Bottom")
		(35 "F.Fab" user "Ref Des/Assembly Top")
		(33 "B.Fab" user "Ref Des/Assembly Bottom")
	)
	(footprint ""
		(layer "F.Cu")
		(at 300.538388 0.002794 180)
		(property "Reference" "J81"
			(at -4.350766 -1.264158 90)
			(unlocked yes)
			(layer "F.SilkS")
			(effects
				(font
					(size 0.7874 0.5842)
					(thickness 0.1524)
				)
				(justify left)
			)
		)
		(property "Value" ""
			(at 0 0 180)
			(layer "F.Fab")
			(effects
				(font
					(size 1.27 1.27)
				)
			)
		)
		(duplicate_pad_numbers_are_jumpers no)
		(fp_line
			(start 1.2192 2.06756)
			(end -1.2192 2.06756)
			(stroke
				(width 0.1524)
				(type default)
			)
			(layer "F.SilkS")
		)
		(fp_line
			(start 1.2192 -2.06756)
			(end 1.2192 2.06756)
			(stroke
				(width 0.1524)
				(type default)
			)
			(layer "F.SilkS")
		)
		(fp_line
			(start -1.2192 2.06756)
			(end -1.2192 -2.06756)
			(stroke
				(width 0.1524)
				(type default)
			)
			(layer "F.SilkS")
		)
		(fp_line
			(start -1.2192 -2.06756)
			(end 1.2192 -2.06756)
			(stroke
				(width 0.1524)
				(type default)
			)
			(layer "F.SilkS")
		)
		(pad "" np_thru_hole circle
			(at -2.8829 -1.27 90)
			(size 1.0414 1.0414)
			(drill 1.0414)
			(layers "*.Cu" "*.Mask")
			(clearance 0.381)
			(thermal_gap 0.381)
		)
		(pad "" np_thru_hole circle
			(at -2.8829 1.27 90)
			(size 1.0414 1.0414)
			(drill 1.0414)
			(layers "*.Cu" "*.Mask")
			(clearance 0.381)
			(thermal_gap 0.381)
		)
		(pad "" np_thru_hole circle
			(at 3.4671 -1.27 90)
			(size 1.0414 1.0414)
			(drill 1.0414)
			(layers "*.Cu" "*.Mask")
			(clearance 0.381)
			(thermal_gap 0.381)
		)
		(pad "" np_thru_hole circle
			(at 3.4671 1.27 90)
			(size 1.0414 1.0414)
			(drill 1.0414)
			(layers "*.Cu" "*.Mask")
			(clearance 0.381)
			(thermal_gap 0.381)
		)
		(pad "1" smd rect
			(at 0.8255 -0.249936 90)
			(size 0.3048 0.508)
			(layers "F.Cu" "F.Mask" "F.Paste")
			(net "DELTA_L_85_10INCH_TOP_DN")
		)
		(pad "2" smd rect
			(at 0.8255 0.249936 90)
			(size 0.3048 0.508)
			(layers "F.Cu" "F.Mask" "F.Paste")
			(net "DELTA_L_85_10INCH_TOP_DP")
		)
		(pad "3" smd circle
			(at 0 0 180)
			(size 0 0)
			(layers "F.Cu" "F.Mask" "F.Paste")
			(net "DELTA_L_GND_1")
		)
		(zone
			(layer "F.Cu")
			(hatch none 0.5)
			(connect_pads
				(clearance 0)
			)
			(min_thickness 0.25)
			(keepout
				(tracks not_allowed)
				(vias allowed)
				(pads allowed)
				(copperpour not_allowed)
				(footprints allowed)
			)
			(placement
				(enabled no)
				(sheetname "")
			)
			(fill
				(thermal_gap 0.5)
				(thermal_bridge_width 0.5)
				(island_removal_mode 0)
			)
			(polygon
				(pts
					(xy 299.420788 0.551434) (xy 299.420788 0.45593) (xy 300.017688 0.45593) (xy 300.017688 0.04953)
					(xy 299.420788 0.04953) (xy 299.420788 -0.043942) (xy 300.017688 -0.043942) (xy 300.017688 -0.450342)
					(xy 299.420788 -0.450342) (xy 299.420788 -0.545846) (xy 300.119288 -0.545846) (xy 300.119288 0.551434)
				)
			)
		)
		(zone
			(layers "F.Cu" "B.Cu" "In1.Cu" "In2.Cu" "In3.Cu" "In4.Cu" "In5.Cu" "In6.Cu"
				"In7.Cu" "In8.Cu" "In9.Cu" "In10.Cu" "In11.Cu" "In12.Cu" "In13.Cu" "In14.Cu"
				"In15.Cu" "In16.Cu"
			)
			(hatch none 0.5)
			(connect_pads
				(clearance 0)
			)
			(min_thickness 0.25)
			(keepout
				(tracks not_allowed)
				(vias allowed)
				(pads allowed)
				(copperpour not_allowed)
				(footprints allowed)
			)
			(placement
				(enabled no)
				(sheetname "")
			)
			(fill
				(thermal_gap 0.5)
				(thermal_bridge_width 0.5)
				(island_removal_mode 0)
			)
			(polygon
				(pts
					(arc
						(start 297.998388 -1.267206)
						(mid 296.144188 -1.267206)
						(end 297.998388 -1.267206)
					)
				)
			)
		)
		(zone
			(layers "F.Cu" "B.Cu" "In1.Cu" "In2.Cu" "In3.Cu" "In4.Cu" "In5.Cu" "In6.Cu"
				"In7.Cu" "In8.Cu" "In9.Cu" "In10.Cu" "In11.Cu" "In12.Cu" "In13.Cu" "In14.Cu"
				"In15.Cu" "In16.Cu"
			)
			(hatch none 0.5)
			(connect_pads
				(clearance 0)
			)
			(min_thickness 0.25)
			(keepout
				(tracks not_allowed)
				(vias allowed)
				(pads allowed)
				(copperpour not_allowed)
				(footprints allowed)
			)
			(placement
				(enabled no)
				(sheetname "")
			)
			(fill
				(thermal_gap 0.5)
				(thermal_bridge_width 0.5)
				(island_removal_mode 0)
			)
			(polygon
				(pts
					(arc
						(start 297.998388 1.272794)
						(mid 296.144188 1.272794)
						(end 297.998388 1.272794)
					)
				)
			)
		)
		(zone
			(layers "F.Cu" "B.Cu" "In1.Cu" "In2.Cu" "In3.Cu" "In4.Cu" "In5.Cu" "In6.Cu"
				"In7.Cu" "In8.Cu" "In9.Cu" "In10.Cu" "In11.Cu" "In12.Cu" "In13.Cu" "In14.Cu"
				"In15.Cu" "In16.Cu"
			)
			(hatch none 0.5)
			(connect_pads
				(clearance 0)
			)
			(min_thickness 0.25)
			(keepout
				(tracks not_allowed)
				(vias allowed)
				(pads allowed)
				(copperpour not_allowed)
				(footprints allowed)
			)
			(placement
				(enabled no)
				(sheetname "")
			)
			(fill
				(thermal_gap 0.5)
				(thermal_bridge_width 0.5)
				(island_removal_mode 0)
			)
			(polygon
				(pts
					(arc
						(start 304.348388 -1.267206)
						(mid 302.494188 -1.267206)
						(end 304.348388 -1.267206)
					)
				)
			)
		)
		(zone
			(layers "F.Cu" "B.Cu" "In1.Cu" "In2.Cu" "In3.Cu" "In4.Cu" "In5.Cu" "In6.Cu"
				"In7.Cu" "In8.Cu" "In9.Cu" "In10.Cu" "In11.Cu" "In12.Cu" "In13.Cu" "In14.Cu"
				"In15.Cu" "In16.Cu"
			)
			(hatch none 0.5)
			(connect_pads
				(clearance 0)
			)
			(min_thickness 0.25)
			(keepout
				(tracks not_allowed)
				(vias allowed)
				(pads allowed)
				(copperpour not_allowed)
				(footprints allowed)
			)
			(placement
				(enabled no)
				(sheetname "")
			)
			(fill
				(thermal_gap 0.5)
				(thermal_bridge_width 0.5)
				(island_removal_mode 0)
			)
			(polygon
				(pts
					(arc
						(start 304.348388 1.272794)
						(mid 302.494188 1.272794)
						(end 304.348388 1.272794)
					)
				)
			)
		)
	)
)
